(kicad_pcb
	(version 20260206)
	(generator "pcbnew")
	(generator_version "10.0")
	(general
		(thickness 1.6)
		(legacy_teardrops no)
	)
	(paper "A4")
	(title_block
		(title "01162023_DA0F0TEBIF0_F0T_Expander_BD_F_brd_V02_OCP.brd")
		(comment 1 "Grand Teton / footprints 9493-9500 of 9728")
	)
	(layers
		(0 "F.Cu" signal "TOP")
		(4 "In1.Cu" signal "GND")
		(6 "In2.Cu" signal "VCC")
		(8 "In3.Cu" signal "VCC1")
		(10 "In4.Cu" signal "GND1")
		(12 "In5.Cu" signal "IN1")
		(14 "In6.Cu" signal "GND2")
		(16 "In7.Cu" signal "IN2")
		(18 "In8.Cu" signal "GND3")
		(20 "In9.Cu" signal "IN3")
		(22 "In10.Cu" signal "GND4")
		(24 "In11.Cu" signal "IN4")
		(26 "In12.Cu" signal "GND5")
		(28 "In13.Cu" signal "IN5")
		(30 "In14.Cu" signal "GND6")
		(32 "In15.Cu" signal "IN6")
		(34 "In16.Cu" signal "GND7")
		(2 "B.Cu" signal "BOTTOM")
		(9 "F.Adhes" user "F.Adhesive")
		(11 "B.Adhes" user "B.Adhesive")
		(13 "F.Paste" user "Package Geometry/Pastemask Top")
		(15 "B.Paste" user "Package Geometry/Pastemask Bottom")
		(5 "F.SilkS" user "Ref Des/Silkscreen Top")
		(7 "B.SilkS" user "Ref Des/Silkscreen Bottom")
		(1 "F.Mask" user "Board Geometry/Soldermask Top")
		(3 "B.Mask" user "Board Geometry/Soldermask Bottom")
		(17 "Dwgs.User" user "User.Drawings")
		(19 "Cmts.User" user "User.Comments")
		(21 "Eco1.User" user "User.Eco1")
		(23 "Eco2.User" user "User.Eco2")
		(25 "Edge.Cuts" user "Board Geometry/Outline")
		(27 "Margin" user)
		(31 "F.CrtYd" user "Package Geometry/Place Bound Top")
		(29 "B.CrtYd" user "Package Geometry/Place Bound Bottom")
		(35 "F.Fab" user "Ref Des/Assembly Top")
		(33 "B.Fab" user "Ref Des/Assembly Bottom")
	)
	(footprint ""
		(layer "B.Cu")
		(at 133.980682 -152.60066)
		(property "Reference" "R5622"
			(at 0 0 0)
			(layer "B.SilkS")
			(hide yes)
			(effects
				(font
					(size 1.27 1.27)
				)
				(justify mirror)
			)
		)
		(property "Value" ""
			(at 0 0 0)
			(layer "B.Fab")
			(effects
				(font
					(size 1.27 1.27)
				)
				(justify mirror)
			)
		)
		(duplicate_pad_numbers_are_jumpers no)
		(fp_line
			(start -0.7874 -0.4064)
			(end -0.7874 0.4064)
			(stroke
				(width 0.1524)
				(type default)
			)
			(layer "B.SilkS")
		)
		(fp_line
			(start -0.7874 0.4064)
			(end 0.7874 0.4064)
			(stroke
				(width 0.1524)
				(type default)
			)
			(layer "B.SilkS")
		)
		(fp_line
			(start 0.7874 -0.4064)
			(end -0.7874 -0.4064)
			(stroke
				(width 0.1524)
				(type default)
			)
			(layer "B.SilkS")
		)
		(fp_line
			(start 0.7874 0.4064)
			(end 0.7874 -0.4064)
			(stroke
				(width 0.1524)
				(type default)
			)
			(layer "B.SilkS")
		)
		(fp_line
			(start -0.67945 -0.3048)
			(end -0.67945 0.3048)
			(stroke
				(width 0.1)
				(type default)
			)
			(layer "B.Fab")
		)
		(fp_line
			(start -0.67945 0.3048)
			(end -0.120396 0.3048)
			(stroke
				(width 0.1)
				(type default)
			)
			(layer "B.Fab")
		)
		(fp_line
			(start -0.12065 -0.3048)
			(end -0.67945 -0.3048)
			(stroke
				(width 0.1)
				(type default)
			)
			(layer "B.Fab")
		)
		(fp_line
			(start -0.12065 -0.2794)
			(end -0.12065 -0.3048)
			(stroke
				(width 0.1)
				(type default)
			)
			(layer "B.Fab")
		)
		(fp_line
			(start -0.120396 0.2794)
			(end 0.12065 0.2794)
			(stroke
				(width 0.1)
				(type default)
			)
			(layer "B.Fab")
		)
		(fp_line
			(start -0.120396 0.3048)
			(end -0.120396 0.2794)
			(stroke
				(width 0.1)
				(type default)
			)
			(layer "B.Fab")
		)
		(fp_line
			(start 0.12065 -0.305054)
			(end 0.12065 -0.2794)
			(stroke
				(width 0.1)
				(type default)
			)
			(layer "B.Fab")
		)
		(fp_line
			(start 0.12065 -0.2794)
			(end -0.12065 -0.2794)
			(stroke
				(width 0.1)
				(type default)
			)
			(layer "B.Fab")
		)
		(fp_line
			(start 0.12065 0.2794)
			(end 0.12065 0.3048)
			(stroke
				(width 0.1)
				(type default)
			)
			(layer "B.Fab")
		)
		(fp_line
			(start 0.12065 0.3048)
			(end 0.67945 0.3048)
			(stroke
				(width 0.1)
				(type default)
			)
			(layer "B.Fab")
		)
		(fp_line
			(start 0.67945 -0.305054)
			(end 0.12065 -0.305054)
			(stroke
				(width 0.1)
				(type default)
			)
			(layer "B.Fab")
		)
		(fp_line
			(start 0.67945 0.3048)
			(end 0.67945 -0.305054)
			(stroke
				(width 0.1)
				(type default)
			)
			(layer "B.Fab")
		)
		(pad "1" smd circle
			(at 0.40005 0 180)
			(size 0 0)
			(layers "B.Cu" "B.Mask" "B.Paste")
			(net "NIC2_ADC_A0")
		)
		(pad "2" smd circle
			(at -0.40005 0 180)
			(size 0 0)
			(layers "B.Cu" "B.Mask" "B.Paste")
			(net "SMB_NIC2_ADC_SDA")
		)
	)
	(footprint ""
		(layer "B.Cu")
		(at 170.524932 -297.79976 -90)
		(property "Reference" "C1394"
			(at 0 0 90)
			(layer "B.SilkS")
			(hide yes)
			(effects
				(font
					(size 1.27 1.27)
				)
				(justify mirror)
			)
		)
		(property "Value" ""
			(at 0 0 90)
			(layer "B.Fab")
			(effects
				(font
					(size 1.27 1.27)
				)
				(justify mirror)
			)
		)
		(duplicate_pad_numbers_are_jumpers no)
		(fp_line
			(start -0.299974 0.150114)
			(end 0.299974 0.150114)
			(stroke
				(width 0.1)
				(type default)
			)
			(layer "B.Fab")
		)
		(fp_line
			(start 0.299974 0.150114)
			(end 0.299974 -0.150114)
			(stroke
				(width 0.1)
				(type default)
			)
			(layer "B.Fab")
		)
		(fp_line
			(start -0.299974 -0.150114)
			(end -0.299974 0.150114)
			(stroke
				(width 0.1)
				(type default)
			)
			(layer "B.Fab")
		)
		(fp_line
			(start 0.299974 -0.150114)
			(end -0.299974 -0.150114)
			(stroke
				(width 0.1)
				(type default)
			)
			(layer "B.Fab")
		)
		(pad "1" smd rect
			(at 0.2667 0 90)
			(size 0.3048 0.381)
			(layers "B.Cu" "B.Mask" "B.Paste")
			(net "P0V8_PEX1")
		)
		(pad "2" smd rect
			(at -0.2667 0 90)
			(size 0.3048 0.381)
			(layers "B.Cu" "B.Mask" "B.Paste")
			(net "GND")
		)
	)
	(footprint ""
		(layer "B.Cu")
		(at 225.871786 -148.786342 180)
		(property "Reference" "C2800"
			(at 0 0 0)
			(layer "B.SilkS")
			(hide yes)
			(effects
				(font
					(size 1.27 1.27)
				)
				(justify mirror)
			)
		)
		(property "Value" ""
			(at 0 0 0)
			(layer "B.Fab")
			(effects
				(font
					(size 1.27 1.27)
				)
				(justify mirror)
			)
		)
		(duplicate_pad_numbers_are_jumpers no)
		(fp_line
			(start 0.7874 0.4064)
			(end 0.7874 -0.4064)
			(stroke
				(width 0.1524)
				(type default)
			)
			(layer "B.SilkS")
		)
		(fp_line
			(start 0.7874 -0.4064)
			(end -0.7874 -0.4064)
			(stroke
				(width 0.1524)
				(type default)
			)
			(layer "B.SilkS")
		)
		(fp_line
			(start -0.7874 0.4064)
			(end 0.7874 0.4064)
			(stroke
				(width 0.1524)
				(type default)
			)
			(layer "B.SilkS")
		)
		(fp_line
			(start -0.7874 -0.4064)
			(end -0.7874 0.4064)
			(stroke
				(width 0.1524)
				(type default)
			)
			(layer "B.SilkS")
		)
		(fp_line
			(start 0.67945 0.3048)
			(end 0.67945 -0.305054)
			(stroke
				(width 0.1)
				(type default)
			)
			(layer "B.Fab")
		)
		(fp_line
			(start 0.67945 -0.305054)
			(end 0.12065 -0.305054)
			(stroke
				(width 0.1)
				(type default)
			)
			(layer "B.Fab")
		)
		(fp_line
			(start 0.12065 0.3048)
			(end 0.67945 0.3048)
			(stroke
				(width 0.1)
				(type default)
			)
			(layer "B.Fab")
		)
		(fp_line
			(start 0.12065 0.2794)
			(end 0.12065 0.3048)
			(stroke
				(width 0.1)
				(type default)
			)
			(layer "B.Fab")
		)
		(fp_line
			(start 0.12065 -0.2794)
			(end -0.12065 -0.2794)
			(stroke
				(width 0.1)
				(type default)
			)
			(layer "B.Fab")
		)
		(fp_line
			(start 0.12065 -0.305054)
			(end 0.12065 -0.2794)
			(stroke
				(width 0.1)
				(type default)
			)
			(layer "B.Fab")
		)
		(fp_line
			(start -0.120396 0.3048)
			(end -0.120396 0.2794)
			(stroke
				(width 0.1)
				(type default)
			)
			(layer "B.Fab")
		)
		(fp_line
			(start -0.120396 0.2794)
			(end 0.12065 0.2794)
			(stroke
				(width 0.1)
				(type default)
			)
			(layer "B.Fab")
		)
		(fp_line
			(start -0.12065 -0.2794)
			(end -0.12065 -0.3048)
			(stroke
				(width 0.1)
				(type default)
			)
			(layer "B.Fab")
		)
		(fp_line
			(start -0.12065 -0.3048)
			(end -0.67945 -0.3048)
			(stroke
				(width 0.1)
				(type default)
			)
			(layer "B.Fab")
		)
		(fp_line
			(start -0.67945 0.3048)
			(end -0.120396 0.3048)
			(stroke
				(width 0.1)
				(type default)
			)
			(layer "B.Fab")
		)
		(fp_line
			(start -0.67945 -0.3048)
			(end -0.67945 0.3048)
			(stroke
				(width 0.1)
				(type default)
			)
			(layer "B.Fab")
		)
		(pad "1" smd circle
			(at 0.40005 0)
			(size 0 0)
			(layers "B.Cu" "B.Mask" "B.Paste")
			(net "P3V3_CLK_GEN_VDDMXCK_CK440_PEX")
		)
		(pad "2" smd circle
			(at -0.40005 0)
			(size 0 0)
			(layers "B.Cu" "B.Mask" "B.Paste")
			(net "GND")
		)
	)
	(footprint ""
		(layer "B.Cu")
		(at 362.53674 -303.649634 -90)
		(property "Reference" "PR18"
			(at 0 0 90)
			(layer "B.SilkS")
			(hide yes)
			(effects
				(font
					(size 1.27 1.27)
				)
				(justify mirror)
			)
		)
		(property "Value" ""
			(at 0 0 90)
			(layer "B.Fab")
			(effects
				(font
					(size 1.27 1.27)
				)
				(justify mirror)
			)
		)
		(duplicate_pad_numbers_are_jumpers no)
		(fp_line
			(start -1.2954 0.5842)
			(end 1.2954 0.5842)
			(stroke
				(width 0.1524)
				(type default)
			)
			(layer "B.SilkS")
		)
		(fp_line
			(start 1.2954 0.5842)
			(end 1.2954 -0.5842)
			(stroke
				(width 0.1524)
				(type default)
			)
			(layer "B.SilkS")
		)
		(fp_line
			(start -1.2954 -0.5842)
			(end -1.2954 0.5842)
			(stroke
				(width 0.1524)
				(type default)
			)
			(layer "B.SilkS")
		)
		(fp_line
			(start 1.2954 -0.5842)
			(end -1.2954 -0.5842)
			(stroke
				(width 0.1524)
				(type default)
			)
			(layer "B.SilkS")
		)
		(fp_line
			(start -0.8636 0.4572)
			(end 0.8636 0.4572)
			(stroke
				(width 0.1)
				(type default)
			)
			(layer "B.Fab")
		)
		(fp_line
			(start 0.8636 0.4572)
			(end 0.8636 0.4318)
			(stroke
				(width 0.1)
				(type default)
			)
			(layer "B.Fab")
		)
		(fp_line
			(start 0.8636 0.4318)
			(end 0.8636 0.4064)
			(stroke
				(width 0.1)
				(type default)
			)
			(layer "B.Fab")
		)
		(fp_line
			(start -1.1938 0.4064)
			(end -0.8636 0.4064)
			(stroke
				(width 0.1)
				(type default)
			)
			(layer "B.Fab")
		)
		(fp_line
			(start -0.8636 0.4064)
			(end -0.8636 0.4572)
			(stroke
				(width 0.1)
				(type default)
			)
			(layer "B.Fab")
		)
		(fp_line
			(start 0.8636 0.4064)
			(end 1.1938 0.4064)
			(stroke
				(width 0.1)
				(type default)
			)
			(layer "B.Fab")
		)
		(fp_line
			(start 1.1938 0.4064)
			(end 1.1938 -0.406654)
			(stroke
				(width 0.1)
				(type default)
			)
			(layer "B.Fab")
		)
		(fp_line
			(start -1.1938 -0.406654)
			(end -1.1938 0.4064)
			(stroke
				(width 0.1)
				(type default)
			)
			(layer "B.Fab")
		)
		(fp_line
			(start -0.8636 -0.406654)
			(end -1.1938 -0.406654)
			(stroke
				(width 0.1)
				(type default)
			)
			(layer "B.Fab")
		)
		(fp_line
			(start 0.8636 -0.406654)
			(end 0.8636 -0.4572)
			(stroke
				(width 0.1)
				(type default)
			)
			(layer "B.Fab")
		)
		(fp_line
			(start 1.1938 -0.406654)
			(end 0.8636 -0.406654)
			(stroke
				(width 0.1)
				(type default)
			)
			(layer "B.Fab")
		)
		(fp_line
			(start -0.8636 -0.4572)
			(end -0.8636 -0.406654)
			(stroke
				(width 0.1)
				(type default)
			)
			(layer "B.Fab")
		)
		(fp_line
			(start 0.8636 -0.4572)
			(end -0.8636 -0.4572)
			(stroke
				(width 0.1)
				(type default)
			)
			(layer "B.Fab")
		)
		(pad "1" smd rect
			(at 0.7366 0 180)
			(size 0.7112 0.8128)
			(layers "B.Cu" "B.Mask" "B.Paste")
			(net "P0V8_PEX3")
		)
		(pad "2" smd rect
			(at -0.7366 0 180)
			(size 0.7112 0.8128)
			(layers "B.Cu" "B.Mask" "B.Paste")
			(net "GND")
		)
	)
	(footprint ""
		(layer "B.Cu")
		(at 281.399742 -288.774886 180)
		(property "Reference" "C3357"
			(at 0 0 0)
			(layer "B.SilkS")
			(hide yes)
			(effects
				(font
					(size 1.27 1.27)
				)
				(justify mirror)
			)
		)
		(property "Value" ""
			(at 0 0 0)
			(layer "B.Fab")
			(effects
				(font
					(size 1.27 1.27)
				)
				(justify mirror)
			)
		)
		(duplicate_pad_numbers_are_jumpers no)
		(fp_line
			(start 0.299974 0.150114)
			(end 0.299974 -0.150114)
			(stroke
				(width 0.1)
				(type default)
			)
			(layer "B.Fab")
		)
		(fp_line
			(start 0.299974 -0.150114)
			(end -0.299974 -0.150114)
			(stroke
				(width 0.1)
				(type default)
			)
			(layer "B.Fab")
		)
		(fp_line
			(start -0.299974 0.150114)
			(end 0.299974 0.150114)
			(stroke
				(width 0.1)
				(type default)
			)
			(layer "B.Fab")
		)
		(fp_line
			(start -0.299974 -0.150114)
			(end -0.299974 0.150114)
			(stroke
				(width 0.1)
				(type default)
			)
			(layer "B.Fab")
		)
		(pad "1" smd rect
			(at 0.2667 0)
			(size 0.3048 0.381)
			(layers "B.Cu" "B.Mask" "B.Paste")
			(net "P1V8_VDDA_PEX2")
		)
		(pad "2" smd rect
			(at -0.2667 0)
			(size 0.3048 0.381)
			(layers "B.Cu" "B.Mask" "B.Paste")
			(net "GND")
		)
	)
	(footprint ""
		(layer "B.Cu")
		(at 161.964116 -143.608552 180)
		(property "Reference" "C878"
			(at 0 0 0)
			(layer "B.SilkS")
			(hide yes)
			(effects
				(font
					(size 1.27 1.27)
				)
				(justify mirror)
			)
		)
		(property "Value" ""
			(at 0 0 0)
			(layer "B.Fab")
			(effects
				(font
					(size 1.27 1.27)
				)
				(justify mirror)
			)
		)
		(duplicate_pad_numbers_are_jumpers no)
		(fp_line
			(start 0.299974 0.150114)
			(end 0.299974 -0.150114)
			(stroke
				(width 0.1)
				(type default)
			)
			(layer "B.Fab")
		)
		(fp_line
			(start 0.299974 -0.150114)
			(end -0.299974 -0.150114)
			(stroke
				(width 0.1)
				(type default)
			)
			(layer "B.Fab")
		)
		(fp_line
			(start -0.299974 0.150114)
			(end 0.299974 0.150114)
			(stroke
				(width 0.1)
				(type default)
			)
			(layer "B.Fab")
		)
		(fp_line
			(start -0.299974 -0.150114)
			(end -0.299974 0.150114)
			(stroke
				(width 0.1)
				(type default)
			)
			(layer "B.Fab")
		)
		(pad "1" smd rect
			(at 0.2667 0)
			(size 0.3048 0.381)
			(layers "B.Cu" "B.Mask" "B.Paste")
			(net "P12V_NIC2")
		)
		(pad "2" smd rect
			(at -0.2667 0)
			(size 0.3048 0.381)
			(layers "B.Cu" "B.Mask" "B.Paste")
			(net "GND")
		)
	)
	(footprint ""
		(layer "B.Cu")
		(at 398.944084 -138.421618 180)
		(property "Reference" "R330"
			(at 0 0 0)
			(layer "B.SilkS")
			(hide yes)
			(effects
				(font
					(size 1.27 1.27)
				)
				(justify mirror)
			)
		)
		(property "Value" ""
			(at 0 0 0)
			(layer "B.Fab")
			(effects
				(font
					(size 1.27 1.27)
				)
				(justify mirror)
			)
		)
		(duplicate_pad_numbers_are_jumpers no)
		(fp_line
			(start 0.7874 0.4064)
			(end 0.7874 -0.4064)
			(stroke
				(width 0.1524)
				(type default)
			)
			(layer "B.SilkS")
		)
		(fp_line
			(start 0.7874 -0.4064)
			(end -0.7874 -0.4064)
			(stroke
				(width 0.1524)
				(type default)
			)
			(layer "B.SilkS")
		)
		(fp_line
			(start -0.7874 0.4064)
			(end 0.7874 0.4064)
			(stroke
				(width 0.1524)
				(type default)
			)
			(layer "B.SilkS")
		)
		(fp_line
			(start -0.7874 -0.4064)
			(end -0.7874 0.4064)
			(stroke
				(width 0.1524)
				(type default)
			)
			(layer "B.SilkS")
		)
		(fp_line
			(start 0.67945 0.3048)
			(end 0.67945 -0.305054)
			(stroke
				(width 0.1)
				(type default)
			)
			(layer "B.Fab")
		)
		(fp_line
			(start 0.67945 -0.305054)
			(end 0.12065 -0.305054)
			(stroke
				(width 0.1)
				(type default)
			)
			(layer "B.Fab")
		)
		(fp_line
			(start 0.12065 0.3048)
			(end 0.67945 0.3048)
			(stroke
				(width 0.1)
				(type default)
			)
			(layer "B.Fab")
		)
		(fp_line
			(start 0.12065 0.2794)
			(end 0.12065 0.3048)
			(stroke
				(width 0.1)
				(type default)
			)
			(layer "B.Fab")
		)
		(fp_line
			(start 0.12065 -0.2794)
			(end -0.12065 -0.2794)
			(stroke
				(width 0.1)
				(type default)
			)
			(layer "B.Fab")
		)
		(fp_line
			(start 0.12065 -0.305054)
			(end 0.12065 -0.2794)
			(stroke
				(width 0.1)
				(type default)
			)
			(layer "B.Fab")
		)
		(fp_line
			(start -0.120396 0.3048)
			(end -0.120396 0.2794)
			(stroke
				(width 0.1)
				(type default)
			)
			(layer "B.Fab")
		)
		(fp_line
			(start -0.120396 0.2794)
			(end 0.12065 0.2794)
			(stroke
				(width 0.1)
				(type default)
			)
			(layer "B.Fab")
		)
		(fp_line
			(start -0.12065 -0.2794)
			(end -0.12065 -0.3048)
			(stroke
				(width 0.1)
				(type default)
			)
			(layer "B.Fab")
		)
		(fp_line
			(start -0.12065 -0.3048)
			(end -0.67945 -0.3048)
			(stroke
				(width 0.1)
				(type default)
			)
			(layer "B.Fab")
		)
		(fp_line
			(start -0.67945 0.3048)
			(end -0.120396 0.3048)
			(stroke
				(width 0.1)
				(type default)
			)
			(layer "B.Fab")
		)
		(fp_line
			(start -0.67945 -0.3048)
			(end -0.67945 0.3048)
			(stroke
				(width 0.1)
				(type default)
			)
			(layer "B.Fab")
		)
		(pad "1" smd circle
			(at 0.40005 0)
			(size 0 0)
			(layers "B.Cu" "B.Mask" "B.Paste")
			(net "NIC6_AUX_PWR_EN")
		)
		(pad "2" smd circle
			(at -0.40005 0)
			(size 0 0)
			(layers "B.Cu" "B.Mask" "B.Paste")
			(net "GND")
		)
	)
	(footprint ""
		(layer "B.Cu")
		(at 348.107 -233.553 90)
		(property "Reference" "R3595"
			(at 0 0 90)
			(layer "B.SilkS")
			(hide yes)
			(effects
				(font
					(size 1.27 1.27)
				)
				(justify mirror)
			)
		)
		(property "Value" ""
			(at 0 0 90)
			(layer "B.Fab")
			(effects
				(font
					(size 1.27 1.27)
				)
				(justify mirror)
			)
		)
		(duplicate_pad_numbers_are_jumpers no)
		(fp_line
			(start 0.7874 -0.4064)
			(end -0.7874 -0.4064)
			(stroke
				(width 0.1524)
				(type default)
			)
			(layer "B.SilkS")
		)
		(fp_line
			(start -0.7874 -0.4064)
			(end -0.7874 0.4064)
			(stroke
				(width 0.1524)
				(type default)
			)
			(layer "B.SilkS")
		)
		(fp_line
			(start 0.7874 0.4064)
			(end 0.7874 -0.4064)
			(stroke
				(width 0.1524)
				(type default)
			)
			(layer "B.SilkS")
		)
		(fp_line
			(start -0.7874 0.4064)
			(end 0.7874 0.4064)
			(stroke
				(width 0.1524)
				(type default)
			)
			(layer "B.SilkS")
		)
		(fp_line
			(start 0.67945 -0.305054)
			(end 0.12065 -0.305054)
			(stroke
				(width 0.1)
				(type default)
			)
			(layer "B.Fab")
		)
		(fp_line
			(start 0.12065 -0.305054)
			(end 0.12065 -0.2794)
			(stroke
				(width 0.1)
				(type default)
			)
			(layer "B.Fab")
		)
		(fp_line
			(start -0.12065 -0.3048)
			(end -0.67945 -0.3048)
			(stroke
				(width 0.1)
				(type default)
			)
			(layer "B.Fab")
		)
		(fp_line
			(start -0.67945 -0.3048)
			(end -0.67945 0.3048)
			(stroke
				(width 0.1)
				(type default)
			)
			(layer "B.Fab")
		)
		(fp_line
			(start 0.12065 -0.2794)
			(end -0.12065 -0.2794)
			(stroke
				(width 0.1)
				(type default)
			)
			(layer "B.Fab")
		)
		(fp_line
			(start -0.12065 -0.2794)
			(end -0.12065 -0.3048)
			(stroke
				(width 0.1)
				(type default)
			)
			(layer "B.Fab")
		)
		(fp_line
			(start 0.12065 0.2794)
			(end 0.12065 0.3048)
			(stroke
				(width 0.1)
				(type default)
			)
			(layer "B.Fab")
		)
		(fp_line
			(start -0.120396 0.2794)
			(end 0.12065 0.2794)
			(stroke
				(width 0.1)
				(type default)
			)
			(layer "B.Fab")
		)
		(fp_line
			(start 0.67945 0.3048)
			(end 0.67945 -0.305054)
			(stroke
				(width 0.1)
				(type default)
			)
			(layer "B.Fab")
		)
		(fp_line
			(start 0.12065 0.3048)
			(end 0.67945 0.3048)
			(stroke
				(width 0.1)
				(type default)
			)
			(layer "B.Fab")
		)
		(fp_line
			(start -0.120396 0.3048)
			(end -0.120396 0.2794)
			(stroke
				(width 0.1)
				(type default)
			)
			(layer "B.Fab")
		)
		(fp_line
			(start -0.67945 0.3048)
			(end -0.120396 0.3048)
			(stroke
				(width 0.1)
				(type default)
			)
			(layer "B.Fab")
		)
		(pad "1" smd circle
			(at 0.40005 0 270)
			(size 0 0)
			(layers "B.Cu" "B.Mask" "B.Paste")
			(net "RST_SSD7_PERST_R_N")
		)
		(pad "2" smd circle
			(at -0.40005 0 270)
			(size 0 0)
			(layers "B.Cu" "B.Mask" "B.Paste")
			(net "RST_SSD7_PERST_N")
		)
	)
)
